# BASEBOARD_FAB2 (Tioga Pass) — schematic netlist excerpt (pin names and nets, part order shuffled) for the footprints in the layout excerpt that follows; sources: Cadence DE-HDL packaged netlist, KiCad conversion of Wiwynn_Tioga_Pass_MB.brd

R2U15  RES  0.0 5% CHIP  pkg 0402  page 107 : A = P3E_CPU0_PE1_SS_RXN<0> ; B = P3E_CPU0_PE1_SS_R_RXN<0>
R1T33  RES  0 5.0% EMPTY  pkg 0603  page 139 : A = P1V5_LAN ; B = P3V3_STBY_P1V5_LAN_I210
R3P26  RES  0.0 5% CHIP  pkg 0402  page 211 : A = FM_PVCCIO_CPU0_EN ; B = VR_PVCCIO_CPU0_EN

(kicad_pcb
	(version 20260206)
	(generator "pcbnew")
	(generator_version "10.0")
	(general
		(thickness 1.6)
		(legacy_teardrops no)
	)
	(paper "A4")
	(title_block
		(title "Wiwynn_Tioga_Pass_MB.brd")
		(comment 1 "Tioga Pass / footprints 3786-3788 of 4770")
	)
	(layers
		(0 "F.Cu" signal "TOP")
		(4 "In1.Cu" signal "L2GND")
		(6 "In2.Cu" signal "L3")
		(8 "In3.Cu" signal "L4GND")
		(10 "In4.Cu" signal "L5")
		(12 "In5.Cu" signal "L6GND")
		(14 "In6.Cu" signal "L7VCC")
		(16 "In7.Cu" signal "L8VCC")
		(18 "In8.Cu" signal "L9GND")
		(20 "In9.Cu" signal "L10")
		(22 "In10.Cu" signal "L11GND")
		(24 "In11.Cu" signal "L12")
		(26 "In12.Cu" signal "L13GND")
		(2 "B.Cu" signal "BOTTOM")
		(9 "F.Adhes" user "F.Adhesive")
		(11 "B.Adhes" user "B.Adhesive")
		(13 "F.Paste" user "Package Geometry/Pastemask Top")
		(15 "B.Paste" user "Package Geometry/Pastemask Bottom")
		(5 "F.SilkS" user "Ref Des/Silkscreen Top")
		(7 "B.SilkS" user "Ref Des/Silkscreen Bottom")
		(1 "F.Mask" user "Board Geometry/Soldermask Top")
		(3 "B.Mask" user "Board Geometry/Soldermask Bottom")
		(17 "Dwgs.User" user "User.Drawings")
		(19 "Cmts.User" user "User.Comments")
		(21 "Eco1.User" user "User.Eco1")
		(23 "Eco2.User" user "User.Eco2")
		(25 "Edge.Cuts" user "Board Geometry/Outline")
		(27 "Margin" user)
		(31 "F.CrtYd" user "Package Geometry/Place Bound Top")
		(29 "B.CrtYd" user "Package Geometry/Place Bound Bottom")
		(35 "F.Fab" user "Ref Des/Assembly Top")
		(33 "B.Fab" user "Ref Des/Assembly Bottom")
	)
	(footprint ""
		(layer "B.Cu")
		(at 334.743806 -60.368434)
		(property "Reference" "R2U15"
			(at 0 0 0)
			(layer "B.SilkS")
			(hide yes)
			(effects
				(font
					(size 1.27 1.27)
				)
				(justify mirror)
			)
		)
		(property "Value" ""
			(at 0 0 0)
			(layer "B.Fab")
			(effects
				(font
					(size 1.27 1.27)
				)
				(justify mirror)
			)
		)
		(duplicate_pad_numbers_are_jumpers no)
		(fp_poly
			(pts
				(xy 0.2794 -0.1016) (xy -0.2794 -0.1016) (xy -0.2794 0.9906) (xy 0.2794 0.9906)
			)
			(stroke
				(width 0)
				(type default)
			)
			(fill no)
			(layer "B.CrtYd")
		)
		(fp_line
			(start -0.2794 -0.1016)
			(end 0.2794 -0.1016)
			(stroke
				(width 0.1)
				(type default)
			)
			(layer "B.Fab")
		)
		(fp_line
			(start -0.2794 0.9906)
			(end -0.2794 -0.1016)
			(stroke
				(width 0.1)
				(type default)
			)
			(layer "B.Fab")
		)
		(fp_line
			(start 0.2794 -0.1016)
			(end 0.2794 0.9906)
			(stroke
				(width 0.1)
				(type default)
			)
			(layer "B.Fab")
		)
		(fp_line
			(start 0.2794 0.9906)
			(end -0.2794 0.9906)
			(stroke
				(width 0.1)
				(type default)
			)
			(layer "B.Fab")
		)
		(pad "1" smd rect
			(at 0 0 180)
			(size 0.508 0.508)
			(layers "B.Cu" "B.Mask" "B.Paste")
			(net "P3E_CPU0_PE1_SS_RXN<0>")
		)
		(pad "2" smd rect
			(at 0 0.889 180)
			(size 0.508 0.508)
			(layers "B.Cu" "B.Mask" "B.Paste")
			(net "P3E_CPU0_PE1_SS_R_RXN<0>")
		)
		(zone
			(layer "B.Cu")
			(hatch none 0.5)
			(connect_pads
				(clearance 0)
			)
			(min_thickness 0.25)
			(keepout
				(tracks allowed)
				(vias not_allowed)
				(pads allowed)
				(copperpour not_allowed)
				(footprints allowed)
			)
			(placement
				(enabled no)
				(sheetname "")
			)
			(fill
				(thermal_gap 0.5)
				(thermal_bridge_width 0.5)
				(island_removal_mode 0)
			)
			(polygon
				(pts
					(xy 334.997806 -60.114434) (xy 334.489806 -60.114434) (xy 334.489806 -59.733434) (xy 334.997806 -59.733434)
				)
			)
		)
		(zone
			(layer "B.Cu")
			(hatch none 0.5)
			(connect_pads
				(clearance 0)
			)
			(min_thickness 0.25)
			(keepout
				(tracks not_allowed)
				(vias allowed)
				(pads allowed)
				(copperpour not_allowed)
				(footprints allowed)
			)
			(placement
				(enabled no)
				(sheetname "")
			)
			(fill
				(thermal_gap 0.5)
				(thermal_bridge_width 0.5)
				(island_removal_mode 0)
			)
			(polygon
				(pts
					(xy 334.997806 -59.733434) (xy 334.489806 -59.733434) (xy 334.489806 -60.114434) (xy 334.997806 -60.114434)
				)
			)
		)
	)
	(footprint ""
		(layer "B.Cu")
		(at 476.4151 -37.5412 90)
		(property "Reference" "R1T33"
			(at 0 0 90)
			(layer "B.SilkS")
			(hide yes)
			(effects
				(font
					(size 1.27 1.27)
				)
				(justify mirror)
			)
		)
		(property "Value" ""
			(at 0 0 90)
			(layer "B.Fab")
			(effects
				(font
					(size 1.27 1.27)
				)
				(justify mirror)
			)
		)
		(duplicate_pad_numbers_are_jumpers no)
		(fp_poly
			(pts
				(xy 0.4953 -0.2032) (xy -0.4953 -0.2032) (xy -0.4953 1.6002) (xy 0.4953 1.6002)
			)
			(stroke
				(width 0)
				(type default)
			)
			(fill no)
			(layer "B.CrtYd")
		)
		(fp_line
			(start 0.4953 -0.2032)
			(end -0.4953 -0.2032)
			(stroke
				(width 0.1)
				(type default)
			)
			(layer "B.Fab")
		)
		(fp_line
			(start -0.4953 -0.2032)
			(end -0.4953 1.6002)
			(stroke
				(width 0.1)
				(type default)
			)
			(layer "B.Fab")
		)
		(fp_line
			(start 0.4953 1.6002)
			(end 0.4953 -0.2032)
			(stroke
				(width 0.1)
				(type default)
			)
			(layer "B.Fab")
		)
		(fp_line
			(start -0.4953 1.6002)
			(end 0.4953 1.6002)
			(stroke
				(width 0.1)
				(type default)
			)
			(layer "B.Fab")
		)
		(pad "1" smd rect
			(at 0 0 270)
			(size 0.762 0.889)
			(layers "B.Cu" "B.Mask" "B.Paste")
			(net "P1V5_LAN")
		)
		(pad "2" smd rect
			(at 0 1.397 270)
			(size 0.762 0.889)
			(layers "B.Cu" "B.Mask" "B.Paste")
			(net "P3V3_STBY_P1V5_LAN_I210")
		)
		(zone
			(layer "B.Cu")
			(hatch none 0.5)
			(connect_pads
				(clearance 0)
			)
			(min_thickness 0.25)
			(keepout
				(tracks not_allowed)
				(vias allowed)
				(pads allowed)
				(copperpour not_allowed)
				(footprints allowed)
			)
			(placement
				(enabled no)
				(sheetname "")
			)
			(fill
				(thermal_gap 0.5)
				(thermal_bridge_width 0.5)
				(island_removal_mode 0)
			)
			(polygon
				(pts
					(xy 477.3676 -37.9222) (xy 476.8596 -37.9222) (xy 476.8596 -37.1602) (xy 477.3676 -37.1602)
				)
			)
		)
		(zone
			(layer "B.Cu")
			(hatch none 0.5)
			(connect_pads
				(clearance 0)
			)
			(min_thickness 0.25)
			(keepout
				(tracks allowed)
				(vias not_allowed)
				(pads allowed)
				(copperpour not_allowed)
				(footprints allowed)
			)
			(placement
				(enabled no)
				(sheetname "")
			)
			(fill
				(thermal_gap 0.5)
				(thermal_bridge_width 0.5)
				(island_removal_mode 0)
			)
			(polygon
				(pts
					(xy 477.3676 -37.1602) (xy 476.8596 -37.1602) (xy 476.8596 -37.9222) (xy 477.3676 -37.9222)
				)
			)
		)
	)
	(footprint ""
		(layer "B.Cu")
		(at 340.741 -82.7024 90)
		(property "Reference" "R3P26"
			(at 0 0 90)
			(layer "B.SilkS")
			(hide yes)
			(effects
				(font
					(size 1.27 1.27)
				)
				(justify mirror)
			)
		)
		(property "Value" ""
			(at 0 0 90)
			(layer "B.Fab")
			(effects
				(font
					(size 1.27 1.27)
				)
				(justify mirror)
			)
		)
		(duplicate_pad_numbers_are_jumpers no)
		(fp_poly
			(pts
				(xy 0.2794 -0.1016) (xy -0.2794 -0.1016) (xy -0.2794 0.9906) (xy 0.2794 0.9906)
			)
			(stroke
				(width 0)
				(type default)
			)
			(fill no)
			(layer "B.CrtYd")
		)
		(fp_line
			(start 0.2794 -0.1016)
			(end 0.2794 0.9906)
			(stroke
				(width 0.1)
				(type default)
			)
			(layer "B.Fab")
		)
		(fp_line
			(start -0.2794 -0.1016)
			(end 0.2794 -0.1016)
			(stroke
				(width 0.1)
				(type default)
			)
			(layer "B.Fab")
		)
		(fp_line
			(start 0.2794 0.9906)
			(end -0.2794 0.9906)
			(stroke
				(width 0.1)
				(type default)
			)
			(layer "B.Fab")
		)
		(fp_line
			(start -0.2794 0.9906)
			(end -0.2794 -0.1016)
			(stroke
				(width 0.1)
				(type default)
			)
			(layer "B.Fab")
		)
		(pad "1" smd rect
			(at 0 0 270)
			(size 0.508 0.508)
			(layers "B.Cu" "B.Mask" "B.Paste")
			(net "FM_PVCCIO_CPU0_EN")
		)
		(pad "2" smd rect
			(at 0 0.889 270)
			(size 0.508 0.508)
			(layers "B.Cu" "B.Mask" "B.Paste")
			(net "VR_PVCCIO_CPU0_EN")
		)
		(zone
			(layer "B.Cu")
			(hatch none 0.5)
			(connect_pads
				(clearance 0)
			)
			(min_thickness 0.25)
			(keepout
				(tracks allowed)
				(vias not_allowed)
				(pads allowed)
				(copperpour not_allowed)
				(footprints allowed)
			)
			(placement
				(enabled no)
				(sheetname "")
			)
			(fill
				(thermal_gap 0.5)
				(thermal_bridge_width 0.5)
				(island_removal_mode 0)
			)
			(polygon
				(pts
					(xy 340.995 -82.9564) (xy 340.995 -82.4484) (xy 341.376 -82.4484) (xy 341.376 -82.9564)
				)
			)
		)
		(zone
			(layer "B.Cu")
			(hatch none 0.5)
			(connect_pads
				(clearance 0)
			)
			(min_thickness 0.25)
			(keepout
				(tracks not_allowed)
				(vias allowed)
				(pads allowed)
				(copperpour not_allowed)
				(footprints allowed)
			)
			(placement
				(enabled no)
				(sheetname "")
			)
			(fill
				(thermal_gap 0.5)
				(thermal_bridge_width 0.5)
				(island_removal_mode 0)
			)
			(polygon
				(pts
					(xy 341.376 -82.9564) (xy 341.376 -82.4484) (xy 340.995 -82.4484) (xy 340.995 -82.9564)
				)
			)
		)
	)
)
